(kicad_pcb
	(version 20260206)
	(generator "pcbnew")
	(generator_version "10.0")
	(general
		(thickness 1.6)
		(legacy_teardrops no)
	)
	(paper "A4")
	(title_block
		(title "03242023_DA0F0TMBIJ0_F0T_Motherboard_J_brd_V01_OCP.brd")
		(comment 1 "Grand Teton / footprints 3820-3825 of 6105")
	)
	(layers
		(0 "F.Cu" signal "TOP")
		(4 "In1.Cu" signal "GND")
		(6 "In2.Cu" signal "IN1")
		(8 "In3.Cu" signal "GND1")
		(10 "In4.Cu" signal "IN2")
		(12 "In5.Cu" signal "GND2")
		(14 "In6.Cu" signal "IN3")
		(16 "In7.Cu" signal "GND3")
		(18 "In8.Cu" signal "VCC")
		(20 "In9.Cu" signal "VCC1")
		(22 "In10.Cu" signal "GND4")
		(24 "In11.Cu" signal "IN4")
		(26 "In12.Cu" signal "GND5")
		(28 "In13.Cu" signal "IN5")
		(30 "In14.Cu" signal "GND6")
		(32 "In15.Cu" signal "IN6")
		(34 "In16.Cu" signal "GND7")
		(2 "B.Cu" signal "BOTTOM")
		(9 "F.Adhes" user "F.Adhesive")
		(11 "B.Adhes" user "B.Adhesive")
		(13 "F.Paste" user "Package Geometry/Pastemask Top")
		(15 "B.Paste" user "Package Geometry/Pastemask Bottom")
		(5 "F.SilkS" user "Ref Des/Silkscreen Top")
		(7 "B.SilkS" user "Ref Des/Silkscreen Bottom")
		(1 "F.Mask" user "Board Geometry/Soldermask Top")
		(3 "B.Mask" user "Board Geometry/Soldermask Bottom")
		(17 "Dwgs.User" user "User.Drawings")
		(19 "Cmts.User" user "User.Comments")
		(21 "Eco1.User" user "User.Eco1")
		(23 "Eco2.User" user "User.Eco2")
		(25 "Edge.Cuts" user "Board Geometry/Outline")
		(27 "Margin" user)
		(31 "F.CrtYd" user "Package Geometry/Place Bound Top")
		(29 "B.CrtYd" user "Package Geometry/Place Bound Bottom")
		(35 "F.Fab" user "Ref Des/Assembly Top")
		(33 "B.Fab" user "Ref Des/Assembly Bottom")
	)
	(footprint ""
		(layer "F.Cu")
		(at 50.256694 -16.099536 90)
		(property "Reference" "C830"
			(at 0 0 90)
			(layer "F.SilkS")
			(hide yes)
			(effects
				(font
					(size 1.27 1.27)
				)
			)
		)
		(property "Value" ""
			(at 0 0 90)
			(layer "F.Fab")
			(effects
				(font
					(size 1.27 1.27)
				)
			)
		)
		(duplicate_pad_numbers_are_jumpers no)
		(fp_line
			(start 0.299974 -0.150114)
			(end 0.299974 0.150114)
			(stroke
				(width 0.1)
				(type default)
			)
			(layer "F.Fab")
		)
		(fp_line
			(start -0.299974 -0.150114)
			(end 0.299974 -0.150114)
			(stroke
				(width 0.1)
				(type default)
			)
			(layer "F.Fab")
		)
		(fp_line
			(start 0.299974 0.150114)
			(end -0.299974 0.150114)
			(stroke
				(width 0.1)
				(type default)
			)
			(layer "F.Fab")
		)
		(fp_line
			(start -0.299974 0.150114)
			(end -0.299974 -0.150114)
			(stroke
				(width 0.1)
				(type default)
			)
			(layer "F.Fab")
		)
		(pad "1" smd rect
			(at -0.2667 0 90)
			(size 0.3048 0.381)
			(layers "F.Cu" "F.Mask" "F.Paste")
			(net "P5E_CPU1_PE1_TX_C_DN<3>")
		)
		(pad "2" smd rect
			(at 0.2667 0 90)
			(size 0.3048 0.381)
			(layers "F.Cu" "F.Mask" "F.Paste")
			(net "P5E_CPU1_PE1_TX_DN<3>")
		)
	)
	(footprint ""
		(layer "F.Cu")
		(at 418.36594 -109.271308 90)
		(property "Reference" "PC2161"
			(at 0 0 90)
			(layer "F.SilkS")
			(hide yes)
			(effects
				(font
					(size 1.27 1.27)
				)
			)
		)
		(property "Value" ""
			(at 0 0 90)
			(layer "F.Fab")
			(effects
				(font
					(size 1.27 1.27)
				)
			)
		)
		(duplicate_pad_numbers_are_jumpers no)
		(fp_line
			(start 0.7874 -0.4064)
			(end 0.7874 0.4064)
			(stroke
				(width 0.1524)
				(type default)
			)
			(layer "F.SilkS")
		)
		(fp_line
			(start -0.7874 -0.4064)
			(end 0.7874 -0.4064)
			(stroke
				(width 0.1524)
				(type default)
			)
			(layer "F.SilkS")
		)
		(fp_line
			(start 0.7874 0.4064)
			(end -0.7874 0.4064)
			(stroke
				(width 0.1524)
				(type default)
			)
			(layer "F.SilkS")
		)
		(fp_line
			(start -0.7874 0.4064)
			(end -0.7874 -0.4064)
			(stroke
				(width 0.1524)
				(type default)
			)
			(layer "F.SilkS")
		)
		(fp_line
			(start -0.12065 -0.305054)
			(end -0.12065 -0.2794)
			(stroke
				(width 0.1)
				(type default)
			)
			(layer "F.Fab")
		)
		(fp_line
			(start -0.67945 -0.305054)
			(end -0.12065 -0.305054)
			(stroke
				(width 0.1)
				(type default)
			)
			(layer "F.Fab")
		)
		(fp_line
			(start 0.67945 -0.3048)
			(end 0.67945 0.3048)
			(stroke
				(width 0.1)
				(type default)
			)
			(layer "F.Fab")
		)
		(fp_line
			(start 0.12065 -0.3048)
			(end 0.67945 -0.3048)
			(stroke
				(width 0.1)
				(type default)
			)
			(layer "F.Fab")
		)
		(fp_line
			(start 0.12065 -0.2794)
			(end 0.12065 -0.3048)
			(stroke
				(width 0.1)
				(type default)
			)
			(layer "F.Fab")
		)
		(fp_line
			(start -0.12065 -0.2794)
			(end 0.12065 -0.2794)
			(stroke
				(width 0.1)
				(type default)
			)
			(layer "F.Fab")
		)
		(fp_line
			(start 0.120396 0.2794)
			(end -0.12065 0.2794)
			(stroke
				(width 0.1)
				(type default)
			)
			(layer "F.Fab")
		)
		(fp_line
			(start -0.12065 0.2794)
			(end -0.12065 0.3048)
			(stroke
				(width 0.1)
				(type default)
			)
			(layer "F.Fab")
		)
		(fp_line
			(start 0.67945 0.3048)
			(end 0.120396 0.3048)
			(stroke
				(width 0.1)
				(type default)
			)
			(layer "F.Fab")
		)
		(fp_line
			(start 0.120396 0.3048)
			(end 0.120396 0.2794)
			(stroke
				(width 0.1)
				(type default)
			)
			(layer "F.Fab")
		)
		(fp_line
			(start -0.12065 0.3048)
			(end -0.67945 0.3048)
			(stroke
				(width 0.1)
				(type default)
			)
			(layer "F.Fab")
		)
		(fp_line
			(start -0.67945 0.3048)
			(end -0.67945 -0.305054)
			(stroke
				(width 0.1)
				(type default)
			)
			(layer "F.Fab")
		)
		(pad "1" smd circle
			(at -0.40005 0 90)
			(size 0 0)
			(layers "F.Cu" "F.Mask" "F.Paste")
			(net "P3V3_OCP_DVDT_1")
		)
		(pad "2" smd circle
			(at 0.40005 0 90)
			(size 0 0)
			(layers "F.Cu" "F.Mask" "F.Paste")
			(net "GND")
		)
	)
	(footprint ""
		(layer "F.Cu")
		(at 424.204892 -384.266948 180)
		(property "Reference" "C1774"
			(at 0 0 180)
			(layer "F.SilkS")
			(hide yes)
			(effects
				(font
					(size 1.27 1.27)
				)
			)
		)
		(property "Value" ""
			(at 0 0 180)
			(layer "F.Fab")
			(effects
				(font
					(size 1.27 1.27)
				)
			)
		)
		(duplicate_pad_numbers_are_jumpers no)
		(fp_line
			(start 0.7874 0.4064)
			(end -0.7874 0.4064)
			(stroke
				(width 0.1524)
				(type default)
			)
			(layer "F.SilkS")
		)
		(fp_line
			(start 0.7874 -0.4064)
			(end 0.7874 0.4064)
			(stroke
				(width 0.1524)
				(type default)
			)
			(layer "F.SilkS")
		)
		(fp_line
			(start -0.7874 0.4064)
			(end -0.7874 -0.4064)
			(stroke
				(width 0.1524)
				(type default)
			)
			(layer "F.SilkS")
		)
		(fp_line
			(start -0.7874 -0.4064)
			(end 0.7874 -0.4064)
			(stroke
				(width 0.1524)
				(type default)
			)
			(layer "F.SilkS")
		)
		(fp_line
			(start 0.67945 0.3048)
			(end 0.120396 0.3048)
			(stroke
				(width 0.1)
				(type default)
			)
			(layer "F.Fab")
		)
		(fp_line
			(start 0.67945 -0.3048)
			(end 0.67945 0.3048)
			(stroke
				(width 0.1)
				(type default)
			)
			(layer "F.Fab")
		)
		(fp_line
			(start 0.12065 -0.2794)
			(end 0.12065 -0.3048)
			(stroke
				(width 0.1)
				(type default)
			)
			(layer "F.Fab")
		)
		(fp_line
			(start 0.12065 -0.3048)
			(end 0.67945 -0.3048)
			(stroke
				(width 0.1)
				(type default)
			)
			(layer "F.Fab")
		)
		(fp_line
			(start 0.120396 0.3048)
			(end 0.120396 0.2794)
			(stroke
				(width 0.1)
				(type default)
			)
			(layer "F.Fab")
		)
		(fp_line
			(start 0.120396 0.2794)
			(end -0.12065 0.2794)
			(stroke
				(width 0.1)
				(type default)
			)
			(layer "F.Fab")
		)
		(fp_line
			(start -0.12065 0.3048)
			(end -0.67945 0.3048)
			(stroke
				(width 0.1)
				(type default)
			)
			(layer "F.Fab")
		)
		(fp_line
			(start -0.12065 0.2794)
			(end -0.12065 0.3048)
			(stroke
				(width 0.1)
				(type default)
			)
			(layer "F.Fab")
		)
		(fp_line
			(start -0.12065 -0.2794)
			(end 0.12065 -0.2794)
			(stroke
				(width 0.1)
				(type default)
			)
			(layer "F.Fab")
		)
		(fp_line
			(start -0.12065 -0.305054)
			(end -0.12065 -0.2794)
			(stroke
				(width 0.1)
				(type default)
			)
			(layer "F.Fab")
		)
		(fp_line
			(start -0.67945 0.3048)
			(end -0.67945 -0.305054)
			(stroke
				(width 0.1)
				(type default)
			)
			(layer "F.Fab")
		)
		(fp_line
			(start -0.67945 -0.305054)
			(end -0.12065 -0.305054)
			(stroke
				(width 0.1)
				(type default)
			)
			(layer "F.Fab")
		)
		(pad "1" smd circle
			(at -0.40005 0 180)
			(size 0 0)
			(layers "F.Cu" "F.Mask" "F.Paste")
			(net "FM_SWB_PWRGD_ISO")
		)
		(pad "2" smd circle
			(at 0.40005 0 180)
			(size 0 0)
			(layers "F.Cu" "F.Mask" "F.Paste")
			(net "GND")
		)
	)
	(footprint ""
		(layer "F.Cu")
		(at 421.15359 -172.113194 -90)
		(property "Reference" "PR1708"
			(at 0 0 270)
			(layer "F.SilkS")
			(hide yes)
			(effects
				(font
					(size 1.27 1.27)
				)
			)
		)
		(property "Value" ""
			(at 0 0 270)
			(layer "F.Fab")
			(effects
				(font
					(size 1.27 1.27)
				)
			)
		)
		(duplicate_pad_numbers_are_jumpers no)
		(fp_line
			(start -0.7874 0.4064)
			(end -0.7874 -0.4064)
			(stroke
				(width 0.1524)
				(type default)
			)
			(layer "F.SilkS")
		)
		(fp_line
			(start 0.7874 0.4064)
			(end -0.7874 0.4064)
			(stroke
				(width 0.1524)
				(type default)
			)
			(layer "F.SilkS")
		)
		(fp_line
			(start -0.7874 -0.4064)
			(end 0.7874 -0.4064)
			(stroke
				(width 0.1524)
				(type default)
			)
			(layer "F.SilkS")
		)
		(fp_line
			(start 0.7874 -0.4064)
			(end 0.7874 0.4064)
			(stroke
				(width 0.1524)
				(type default)
			)
			(layer "F.SilkS")
		)
		(fp_line
			(start -0.67945 0.3048)
			(end -0.67945 -0.305054)
			(stroke
				(width 0.1)
				(type default)
			)
			(layer "F.Fab")
		)
		(fp_line
			(start -0.12065 0.3048)
			(end -0.67945 0.3048)
			(stroke
				(width 0.1)
				(type default)
			)
			(layer "F.Fab")
		)
		(fp_line
			(start 0.120396 0.3048)
			(end 0.120396 0.2794)
			(stroke
				(width 0.1)
				(type default)
			)
			(layer "F.Fab")
		)
		(fp_line
			(start 0.67945 0.3048)
			(end 0.120396 0.3048)
			(stroke
				(width 0.1)
				(type default)
			)
			(layer "F.Fab")
		)
		(fp_line
			(start -0.12065 0.2794)
			(end -0.12065 0.3048)
			(stroke
				(width 0.1)
				(type default)
			)
			(layer "F.Fab")
		)
		(fp_line
			(start 0.120396 0.2794)
			(end -0.12065 0.2794)
			(stroke
				(width 0.1)
				(type default)
			)
			(layer "F.Fab")
		)
		(fp_line
			(start -0.12065 -0.2794)
			(end 0.12065 -0.2794)
			(stroke
				(width 0.1)
				(type default)
			)
			(layer "F.Fab")
		)
		(fp_line
			(start 0.12065 -0.2794)
			(end 0.12065 -0.3048)
			(stroke
				(width 0.1)
				(type default)
			)
			(layer "F.Fab")
		)
		(fp_line
			(start 0.12065 -0.3048)
			(end 0.67945 -0.3048)
			(stroke
				(width 0.1)
				(type default)
			)
			(layer "F.Fab")
		)
		(fp_line
			(start 0.67945 -0.3048)
			(end 0.67945 0.3048)
			(stroke
				(width 0.1)
				(type default)
			)
			(layer "F.Fab")
		)
		(fp_line
			(start -0.67945 -0.305054)
			(end -0.12065 -0.305054)
			(stroke
				(width 0.1)
				(type default)
			)
			(layer "F.Fab")
		)
		(fp_line
			(start -0.12065 -0.305054)
			(end -0.12065 -0.2794)
			(stroke
				(width 0.1)
				(type default)
			)
			(layer "F.Fab")
		)
		(pad "1" smd circle
			(at -0.40005 0 270)
			(size 0 0)
			(layers "F.Cu" "F.Mask" "F.Paste")
			(net "PVCCINFAON_CPU0_LSET1")
		)
		(pad "2" smd circle
			(at 0.40005 0 270)
			(size 0 0)
			(layers "F.Cu" "F.Mask" "F.Paste")
			(net "GND")
		)
	)
	(footprint ""
		(layer "F.Cu")
		(at 36.956238 -127.71374)
		(property "Reference" "C2451"
			(at 0 0 0)
			(layer "F.SilkS")
			(hide yes)
			(effects
				(font
					(size 1.27 1.27)
				)
			)
		)
		(property "Value" ""
			(at 0 0 0)
			(layer "F.Fab")
			(effects
				(font
					(size 1.27 1.27)
				)
			)
		)
		(duplicate_pad_numbers_are_jumpers no)
		(fp_line
			(start -0.7874 -0.4064)
			(end 0.7874 -0.4064)
			(stroke
				(width 0.1524)
				(type default)
			)
			(layer "F.SilkS")
		)
		(fp_line
			(start -0.7874 0.4064)
			(end -0.7874 -0.4064)
			(stroke
				(width 0.1524)
				(type default)
			)
			(layer "F.SilkS")
		)
		(fp_line
			(start 0.7874 -0.4064)
			(end 0.7874 0.4064)
			(stroke
				(width 0.1524)
				(type default)
			)
			(layer "F.SilkS")
		)
		(fp_line
			(start 0.7874 0.4064)
			(end -0.7874 0.4064)
			(stroke
				(width 0.1524)
				(type default)
			)
			(layer "F.SilkS")
		)
		(fp_line
			(start -0.67945 -0.305054)
			(end -0.12065 -0.305054)
			(stroke
				(width 0.1)
				(type default)
			)
			(layer "F.Fab")
		)
		(fp_line
			(start -0.67945 0.3048)
			(end -0.67945 -0.305054)
			(stroke
				(width 0.1)
				(type default)
			)
			(layer "F.Fab")
		)
		(fp_line
			(start -0.12065 -0.305054)
			(end -0.12065 -0.2794)
			(stroke
				(width 0.1)
				(type default)
			)
			(layer "F.Fab")
		)
		(fp_line
			(start -0.12065 -0.2794)
			(end 0.12065 -0.2794)
			(stroke
				(width 0.1)
				(type default)
			)
			(layer "F.Fab")
		)
		(fp_line
			(start -0.12065 0.2794)
			(end -0.12065 0.3048)
			(stroke
				(width 0.1)
				(type default)
			)
			(layer "F.Fab")
		)
		(fp_line
			(start -0.12065 0.3048)
			(end -0.67945 0.3048)
			(stroke
				(width 0.1)
				(type default)
			)
			(layer "F.Fab")
		)
		(fp_line
			(start 0.120396 0.2794)
			(end -0.12065 0.2794)
			(stroke
				(width 0.1)
				(type default)
			)
			(layer "F.Fab")
		)
		(fp_line
			(start 0.120396 0.3048)
			(end 0.120396 0.2794)
			(stroke
				(width 0.1)
				(type default)
			)
			(layer "F.Fab")
		)
		(fp_line
			(start 0.12065 -0.3048)
			(end 0.67945 -0.3048)
			(stroke
				(width 0.1)
				(type default)
			)
			(layer "F.Fab")
		)
		(fp_line
			(start 0.12065 -0.2794)
			(end 0.12065 -0.3048)
			(stroke
				(width 0.1)
				(type default)
			)
			(layer "F.Fab")
		)
		(fp_line
			(start 0.67945 -0.3048)
			(end 0.67945 0.3048)
			(stroke
				(width 0.1)
				(type default)
			)
			(layer "F.Fab")
		)
		(fp_line
			(start 0.67945 0.3048)
			(end 0.120396 0.3048)
			(stroke
				(width 0.1)
				(type default)
			)
			(layer "F.Fab")
		)
		(pad "1" smd circle
			(at -0.40005 0)
			(size 0 0)
			(layers "F.Cu" "F.Mask" "F.Paste")
			(net "PVCCINFAON_CPU1_EN_R")
		)
		(pad "2" smd circle
			(at 0.40005 0)
			(size 0 0)
			(layers "F.Cu" "F.Mask" "F.Paste")
			(net "GND")
		)
	)
	(footprint ""
		(layer "F.Cu")
		(at 461.53705 -41.002458)
		(property "Reference" "Q124"
			(at -3.73507 -2.576576 0)
			(unlocked yes)
			(layer "F.SilkS")
			(effects
				(font
					(size 0.7874 0.5842)
					(thickness 0.1524)
				)
				(justify left)
			)
		)
		(property "Value" ""
			(at 0 0 0)
			(layer "F.Fab")
			(effects
				(font
					(size 1.27 1.27)
				)
			)
		)
		(duplicate_pad_numbers_are_jumpers no)
		(fp_line
			(start -1.332738 -1.100074)
			(end -0.4826 -1.100074)
			(stroke
				(width 0.1524)
				(type default)
			)
			(layer "F.SilkS")
		)
		(fp_line
			(start -1.332738 1.100074)
			(end -1.332738 -1.100074)
			(stroke
				(width 0.1524)
				(type default)
			)
			(layer "F.SilkS")
		)
		(fp_line
			(start -0.4826 -1.100074)
			(end 0 -0.541274)
			(stroke
				(width 0.1524)
				(type default)
			)
			(layer "F.SilkS")
		)
		(fp_line
			(start 0 -0.541274)
			(end 0.4826 -1.100074)
			(stroke
				(width 0.1524)
				(type default)
			)
			(layer "F.SilkS")
		)
		(fp_line
			(start 0.4826 -1.100074)
			(end 1.332738 -1.100074)
			(stroke
				(width 0.1524)
				(type default)
			)
			(layer "F.SilkS")
		)
		(fp_line
			(start 1.332738 -1.100074)
			(end 1.332738 1.100074)
			(stroke
				(width 0.1524)
				(type default)
			)
			(layer "F.SilkS")
		)
		(fp_line
			(start 1.332738 1.100074)
			(end -1.332738 1.100074)
			(stroke
				(width 0.1524)
				(type default)
			)
			(layer "F.SilkS")
		)
		(fp_poly
			(pts
				(xy -0.672846 -2.01422) (xy -1.023874 -1.312164) (xy -1.374902 -2.01422)
			)
			(stroke
				(width 0)
				(type default)
			)
			(fill yes)
			(layer "F.SilkS")
		)
		(fp_line
			(start -0.674878 -1.100074)
			(end 0.674878 -1.100074)
			(stroke
				(width 0.1)
				(type default)
			)
			(layer "F.Fab")
		)
		(fp_line
			(start -0.674878 1.100074)
			(end -0.674878 -1.100074)
			(stroke
				(width 0.1)
				(type default)
			)
			(layer "F.Fab")
		)
		(fp_line
			(start 0.674878 -1.100074)
			(end 0.674878 1.100074)
			(stroke
				(width 0.1)
				(type default)
			)
			(layer "F.Fab")
		)
		(fp_line
			(start 0.674878 1.100074)
			(end -0.674878 1.100074)
			(stroke
				(width 0.1)
				(type default)
			)
			(layer "F.Fab")
		)
		(fp_poly
			(pts
				(xy -2.2352 -0.298958) (xy -2.2352 -1.001014) (xy -1.533144 -0.649986)
			)
			(stroke
				(width 0)
				(type default)
			)
			(fill yes)
			(layer "F.Fab")
		)
		(pad "1" smd rect
			(at -0.94996 -0.649986 90)
			(size 0.4318 0.508)
			(layers "F.Cu" "F.Mask" "F.Paste")
			(net "GND")
		)
		(pad "2" smd rect
			(at -0.94996 0 90)
			(size 0.4318 0.508)
			(layers "F.Cu" "F.Mask" "F.Paste")
			(net "P3V3_OCP_EN_1_R")
		)
		(pad "3" smd rect
			(at -0.94996 0.649986 90)
			(size 0.4318 0.508)
			(layers "F.Cu" "F.Mask" "F.Paste")
			(net "P3V3_OCP_UV_1_R1")
		)
		(pad "4" smd rect
			(at 0.94996 0.649986 90)
			(size 0.4318 0.508)
			(layers "F.Cu" "F.Mask" "F.Paste")
			(net "GND")
		)
		(pad "5" smd rect
			(at 0.94996 0 90)
			(size 0.4318 0.508)
			(layers "F.Cu" "F.Mask" "F.Paste")
			(net "P3V3_OCP_1_EN_G")
		)
		(pad "6" smd rect
			(at 0.94996 -0.649986 90)
			(size 0.4318 0.508)
			(layers "F.Cu" "F.Mask" "F.Paste")
			(net "P3V3_OCP_1_EN_G")
		)
	)
)
